(kicad_pcb
	(version 20260206)
	(generator "pcbnew")
	(generator_version "10.0")
	(general
		(thickness 1.6)
		(legacy_teardrops no)
	)
	(paper "A4")
	(title_block
		(title "dpb — 14545-sa.0730WZS0815.brd")
		(comment 1 "Honey Badger (Wiwynn) / footprints 926-931 of 1066")
	)
	(layers
		(0 "F.Cu" signal "TOP")
		(4 "In1.Cu" signal "L2GND")
		(6 "In2.Cu" signal "L3")
		(8 "In3.Cu" signal "L4VCC")
		(10 "In4.Cu" signal "L5VCC")
		(12 "In5.Cu" signal "L6")
		(14 "In6.Cu" signal "L7GND")
		(2 "B.Cu" signal "BOTTOM")
		(9 "F.Adhes" user "F.Adhesive")
		(11 "B.Adhes" user "B.Adhesive")
		(13 "F.Paste" user "Package Geometry/Pastemask Top")
		(15 "B.Paste" user "Package Geometry/Pastemask Bottom")
		(5 "F.SilkS" user "Ref Des/Silkscreen Top")
		(7 "B.SilkS" user "Ref Des/Silkscreen Bottom")
		(1 "F.Mask" user "Board Geometry/Soldermask Top")
		(3 "B.Mask" user "Board Geometry/Soldermask Bottom")
		(17 "Dwgs.User" user "User.Drawings")
		(19 "Cmts.User" user "User.Comments")
		(21 "Eco1.User" user "User.Eco1")
		(23 "Eco2.User" user "User.Eco2")
		(25 "Edge.Cuts" user "Board Geometry/Outline")
		(27 "Margin" user)
		(31 "F.CrtYd" user "Package Geometry/Place Bound Top")
		(29 "B.CrtYd" user "Package Geometry/Place Bound Bottom")
		(35 "F.Fab" user "Ref Des/Assembly Top")
		(33 "B.Fab" user "Ref Des/Assembly Bottom")
	)
	(footprint ""
		(layer "F.Cu")
		(at 78.612746 -193.6877 90)
		(property "Reference" "R222"
			(at 0 0 90)
			(layer "F.SilkS")
			(hide yes)
			(effects
				(font
					(size 1.27 1.27)
				)
			)
		)
		(property "Value" "200KR2F-L-GP"
			(at 0.064008 -3.993896 90)
			(unlocked yes)
			(layer "F.Fab")
			(hide yes)
			(effects
				(font
					(size 1.016 1.016)
					(thickness 0.1524)
				)
			)
		)
		(property "Device Type" "R402H16"
			(at 0.064008 -5.517896 90)
			(unlocked yes)
			(layer "F.Fab")
			(hide yes)
			(effects
				(font
					(size 1.016 1.016)
					(thickness 0.1524)
				)
			)
		)
		(duplicate_pad_numbers_are_jumpers no)
		(fp_line
			(start 0.508 -0.9398)
			(end -0.508 -0.9398)
			(stroke
				(width 0.1524)
				(type default)
			)
			(layer "F.SilkS")
		)
		(fp_line
			(start -0.508 -0.9398)
			(end -0.508 0.9398)
			(stroke
				(width 0.1524)
				(type default)
			)
			(layer "F.SilkS")
		)
		(fp_rect
			(start -0.508 0.9398)
			(end 0.508 -0.9398)
			(stroke
				(width 0)
				(type default)
			)
			(fill no)
			(layer "F.CrtYd")
		)
		(fp_rect
			(start -0.508 0.9398)
			(end 0.508 -0.9398)
			(stroke
				(width 0)
				(type default)
			)
			(fill no)
			(layer "F.Fab")
		)
		(pad "1" smd custom
			(at 0 -0.4445 90)
			(size 0.1397 0.1397)
			(layers "F.Cu" "F.Mask" "F.Paste")
			(net "P12V")
			(options
				(clearance outline)
				(anchor circle)
			)
			(primitives
				(gr_poly
					(pts
						(arc
							(start -0.1778 -0.2794)
							(mid -0.249642 -0.249642)
							(end -0.2794 -0.1778)
						)
						(arc
							(start -0.2794 0.1778)
							(mid -0.249642 0.249642)
							(end -0.1778 0.2794)
						)
						(arc
							(start 0.1778 0.2794)
							(mid 0.249642 0.249642)
							(end 0.2794 0.1778)
						)
						(arc
							(start 0.2794 -0.1778)
							(mid 0.249642 -0.249642)
							(end 0.1778 -0.2794)
						)
					)
					(width 0)
					(fill yes)
				)
			)
		)
		(pad "2" smd custom
			(at 0 0.4445 90)
			(size 0.1397 0.1397)
			(layers "F.Cu" "F.Mask" "F.Paste")
			(net "SW_HDD8_P")
			(options
				(clearance outline)
				(anchor circle)
			)
			(primitives
				(gr_poly
					(pts
						(arc
							(start -0.1778 -0.2794)
							(mid -0.249642 -0.249642)
							(end -0.2794 -0.1778)
						)
						(arc
							(start -0.2794 0.1778)
							(mid -0.249642 0.249642)
							(end -0.1778 0.2794)
						)
						(arc
							(start 0.1778 0.2794)
							(mid 0.249642 0.249642)
							(end 0.2794 0.1778)
						)
						(arc
							(start 0.2794 -0.1778)
							(mid 0.249642 -0.249642)
							(end 0.1778 -0.2794)
						)
					)
					(width 0)
					(fill yes)
				)
			)
		)
	)
	(footprint ""
		(layer "F.Cu")
		(at 7.499858 -78.629764)
		(property "Reference" "H6"
			(at 0 0 0)
			(layer "F.SilkS")
			(hide yes)
			(effects
				(font
					(size 1.27 1.27)
				)
			)
		)
		(property "Value" "HOLE315R140"
			(at 0 -7.5692 0)
			(unlocked yes)
			(layer "F.Fab")
			(hide yes)
			(effects
				(font
					(size 1.016 1.016)
					(thickness 0.1524)
				)
			)
		)
		(property "Device Type" "HOLE315R140"
			(at 0 -9.0932 0)
			(unlocked yes)
			(layer "F.Fab")
			(hide yes)
			(effects
				(font
					(size 1.016 1.016)
					(thickness 0.1524)
				)
			)
		)
		(duplicate_pad_numbers_are_jumpers no)
		(fp_poly
			(pts
				(arc
					(start 4.3053 0)
					(mid -4.3053 0)
					(end 4.3053 0)
				)
			)
			(stroke
				(width 0)
				(type default)
			)
			(fill no)
			(layer "F.CrtYd")
		)
		(fp_poly
			(pts
				(arc
					(start 4.3053 0)
					(mid -4.3053 0)
					(end 4.3053 0)
				)
			)
			(stroke
				(width 0)
				(type default)
			)
			(fill no)
			(layer "F.Fab")
		)
		(pad "1" thru_hole circle
			(at 0.00127 0.00127)
			(size 8.001 8.001)
			(drill 3.556)
			(layers "*.Cu" "*.Mask")
			(remove_unused_layers no)
			(net "GND")
			(clearance -1.7145)
			(thermal_gap 0.3048)
			(padstack
				(mode front_inner_back)
				(layer "Inner"
					(shape circle)
					(size 3.9624 3.9624)
					(clearance 0.3048)
				)
				(layer "B.Cu"
					(shape circle)
					(size 8.001 8.001)
					(clearance -1.7145)
				)
			)
		)
	)
	(footprint ""
		(layer "F.Cu")
		(at 215.773 -86.6902 180)
		(property "Reference" "C176"
			(at 0 0 180)
			(layer "F.SilkS")
			(hide yes)
			(effects
				(font
					(size 1.27 1.27)
				)
			)
		)
		(property "Value" "SC10U25V6KX-1GP"
			(at -0.0762 -5.1308 180)
			(unlocked yes)
			(layer "F.Fab")
			(hide yes)
			(effects
				(font
					(size 1.016 1.016)
					(thickness 0.1524)
				)
			)
		)
		(property "Device Type" "C1206H71"
			(at -0.127 -6.6548 180)
			(unlocked yes)
			(layer "F.Fab")
			(hide yes)
			(effects
				(font
					(size 1.016 1.016)
					(thickness 0.1524)
				)
			)
		)
		(duplicate_pad_numbers_are_jumpers no)
		(fp_line
			(start 1.016 2.2352)
			(end -1.016 2.2352)
			(stroke
				(width 0.1524)
				(type default)
			)
			(layer "F.SilkS")
		)
		(fp_line
			(start 1.016 0.8382)
			(end 1.016 2.2352)
			(stroke
				(width 0.1524)
				(type default)
			)
			(layer "F.SilkS")
		)
		(fp_line
			(start 1.016 -2.2352)
			(end 1.016 -0.8382)
			(stroke
				(width 0.1524)
				(type default)
			)
			(layer "F.SilkS")
		)
		(fp_line
			(start -1.016 2.2352)
			(end -1.016 0.8382)
			(stroke
				(width 0.1524)
				(type default)
			)
			(layer "F.SilkS")
		)
		(fp_line
			(start -1.016 -0.8382)
			(end -1.016 -2.2352)
			(stroke
				(width 0.1524)
				(type default)
			)
			(layer "F.SilkS")
		)
		(fp_line
			(start -1.016 -2.2352)
			(end 1.016 -2.2352)
			(stroke
				(width 0.1524)
				(type default)
			)
			(layer "F.SilkS")
		)
		(fp_rect
			(start -1.0922 2.3114)
			(end 1.0922 -2.3114)
			(stroke
				(width 0)
				(type default)
			)
			(fill no)
			(layer "F.CrtYd")
		)
		(fp_poly
			(pts
				(xy 1.0922 -2.3114) (xy 1.0922 2.3114) (xy -1.0922 2.3114) (xy -1.0922 -2.3114)
			)
			(stroke
				(width 0)
				(type default)
			)
			(fill no)
			(layer "F.Fab")
		)
		(pad "1" smd rect
			(at 0 -1.397 180)
			(size 1.651 1.27)
			(layers "F.Cu" "F.Mask" "F.Paste")
			(net "P12V_HDD4")
		)
		(pad "2" smd rect
			(at 0 1.397 180)
			(size 1.651 1.27)
			(layers "F.Cu" "F.Mask" "F.Paste")
			(net "GND")
		)
	)
	(footprint ""
		(layer "F.Cu")
		(at 33.019746 -64.1477 -90)
		(property "Reference" "C249"
			(at 0 0 270)
			(layer "F.SilkS")
			(hide yes)
			(effects
				(font
					(size 1.27 1.27)
				)
			)
		)
		(property "Value" "SCD01U50V2KX-1GP"
			(at 1.1811 -2.7051 270)
			(unlocked yes)
			(layer "F.Fab")
			(hide yes)
			(effects
				(font
					(size 1.016 1.016)
					(thickness 0.1524)
				)
			)
		)
		(property "Device Type" "C402H22"
			(at 1.1811 -4.2291 270)
			(unlocked yes)
			(layer "F.Fab")
			(hide yes)
			(effects
				(font
					(size 1.016 1.016)
					(thickness 0.1524)
				)
			)
		)
		(duplicate_pad_numbers_are_jumpers no)
		(fp_rect
			(start -0.4318 0.9525)
			(end 0.4318 -0.9525)
			(stroke
				(width 0)
				(type default)
			)
			(fill no)
			(layer "F.CrtYd")
		)
		(fp_rect
			(start -0.4318 0.9525)
			(end 0.4318 -0.9525)
			(stroke
				(width 0)
				(type default)
			)
			(fill no)
			(layer "F.Fab")
		)
		(pad "1" smd custom
			(at 0 -0.4445 270)
			(size 0.1524 0.1524)
			(layers "F.Cu" "F.Mask" "F.Paste")
			(net "SAS2X28_DRIVE_RX_P_B9")
			(options
				(clearance outline)
				(anchor circle)
			)
			(primitives
				(gr_poly
					(pts
						(arc
							(start 0.3048 -0.2032)
							(mid 0.275042 -0.275042)
							(end 0.2032 -0.3048)
						)
						(arc
							(start -0.2032 -0.3048)
							(mid -0.275042 -0.275042)
							(end -0.3048 -0.2032)
						)
						(arc
							(start -0.3048 0.2032)
							(mid -0.275042 0.275042)
							(end -0.2032 0.3048)
						)
						(arc
							(start 0.2032 0.3048)
							(mid 0.275042 0.275042)
							(end 0.3048 0.2032)
						)
					)
					(width 0)
					(fill yes)
				)
			)
		)
		(pad "2" smd custom
			(at 0 0.4445 270)
			(size 0.1524 0.1524)
			(layers "F.Cu" "F.Mask" "F.Paste")
			(net "SAS2X28_B_HDD9_RX_+")
			(options
				(clearance outline)
				(anchor circle)
			)
			(primitives
				(gr_poly
					(pts
						(arc
							(start 0.3048 -0.2032)
							(mid 0.275042 -0.275042)
							(end 0.2032 -0.3048)
						)
						(arc
							(start -0.2032 -0.3048)
							(mid -0.275042 -0.275042)
							(end -0.3048 -0.2032)
						)
						(arc
							(start -0.3048 0.2032)
							(mid -0.275042 0.275042)
							(end -0.2032 0.3048)
						)
						(arc
							(start 0.2032 0.3048)
							(mid 0.275042 0.275042)
							(end 0.3048 0.2032)
						)
					)
					(width 0)
					(fill yes)
				)
			)
		)
	)
	(footprint ""
		(layer "F.Cu")
		(at 22.987 -282.702 -90)
		(property "Reference" "D30"
			(at 0 0 270)
			(layer "F.SilkS")
			(hide yes)
			(effects
				(font
					(size 1.27 1.27)
				)
			)
		)
		(property "Value" "RB551V30-1-GP"
			(at 0 -6.7818 270)
			(unlocked yes)
			(layer "F.Fab")
			(hide yes)
			(effects
				(font
					(size 1.016 1.016)
					(thickness 0.1524)
				)
			)
		)
		(property "Device Type" "SOD323AKH44"
			(at 0 -8.6868 270)
			(unlocked yes)
			(layer "F.Fab")
			(hide yes)
			(effects
				(font
					(size 1.016 1.016)
					(thickness 0.1524)
				)
			)
		)
		(duplicate_pad_numbers_are_jumpers no)
		(fp_line
			(start -0.889 2.159)
			(end -0.889 -1.9304)
			(stroke
				(width 0.1524)
				(type default)
			)
			(layer "F.SilkS")
		)
		(fp_line
			(start 0.889 2.159)
			(end -0.889 2.159)
			(stroke
				(width 0.1524)
				(type default)
			)
			(layer "F.SilkS")
		)
		(fp_line
			(start 0.762 2.0574)
			(end -0.762 2.0574)
			(stroke
				(width 0.508)
				(type default)
			)
			(layer "F.SilkS")
		)
		(fp_line
			(start -0.889 -1.9304)
			(end 0.889 -1.9304)
			(stroke
				(width 0.1524)
				(type default)
			)
			(layer "F.SilkS")
		)
		(fp_line
			(start 0.889 -1.9304)
			(end 0.889 2.159)
			(stroke
				(width 0.1524)
				(type default)
			)
			(layer "F.SilkS")
		)
		(fp_rect
			(start -1.016 2.3114)
			(end 1.016 -2.0066)
			(stroke
				(width 0)
				(type default)
			)
			(fill no)
			(layer "F.CrtYd")
		)
		(fp_poly
			(pts
				(xy -1.016 -2.0066) (xy 1.016 -2.0066) (xy 1.016 2.3114) (xy -1.016 2.3114)
			)
			(stroke
				(width 0)
				(type default)
			)
			(fill no)
			(layer "F.Fab")
		)
		(pad "A" smd rect
			(at 0 -1.143 270)
			(size 0.5588 1.016)
			(layers "F.Cu" "F.Mask" "F.Paste")
			(net "SW_HDD7_R")
		)
		(pad "K" smd rect
			(at 0 1.143 270)
			(size 0.5588 1.016)
			(layers "F.Cu" "F.Mask" "F.Paste")
			(net "SW_HDD7_N")
		)
	)
	(footprint ""
		(layer "F.Cu")
		(at 53.511704 -18.422112 90)
		(property "Reference" "PU2"
			(at 0 0 90)
			(layer "F.SilkS")
			(hide yes)
			(effects
				(font
					(size 1.27 1.27)
				)
			)
		)
		(property "Value" "TPS53319DQPR-GP"
			(at 4.7498 -5.6896 90)
			(unlocked yes)
			(layer "F.Fab")
			(hide yes)
			(effects
				(font
					(size 1.016 1.016)
					(thickness 0.1524)
				)
			)
		)
		(property "Device Type" "QFN22G6050-G6133H60"
			(at 4.7498 -7.2136 90)
			(unlocked yes)
			(layer "F.Fab")
			(hide yes)
			(effects
				(font
					(size 1.016 1.016)
					(thickness 0.1524)
				)
			)
		)
		(duplicate_pad_numbers_are_jumpers no)
		(fp_line
			(start -2.286 -3.5179)
			(end -3.556 -3.5179)
			(stroke
				(width 0.1524)
				(type default)
			)
			(layer "F.SilkS")
		)
		(fp_line
			(start -3.556 -3.5179)
			(end -3.556 -2.2479)
			(stroke
				(width 0.1524)
				(type default)
			)
			(layer "F.SilkS")
		)
		(fp_line
			(start 0.500126 -3.262122)
			(end 0.500126 -3.770122)
			(stroke
				(width 0.1524)
				(type default)
			)
			(layer "F.SilkS")
		)
		(fp_line
			(start -1.999996 -3.262122)
			(end -1.999996 -4.024122)
			(stroke
				(width 0.1524)
				(type default)
			)
			(layer "F.SilkS")
		)
		(fp_line
			(start -3.556 2.2479)
			(end -3.556 3.5179)
			(stroke
				(width 0.1524)
				(type default)
			)
			(layer "F.SilkS")
		)
		(fp_line
			(start 1.500124 3.262122)
			(end 1.500124 4.024122)
			(stroke
				(width 0.1524)
				(type default)
			)
			(layer "F.SilkS")
		)
		(fp_line
			(start -0.999998 3.262122)
			(end -0.999998 3.770122)
			(stroke
				(width 0.1524)
				(type default)
			)
			(layer "F.SilkS")
		)
		(fp_line
			(start 3.556 3.5179)
			(end 3.556 2.2479)
			(stroke
				(width 0.1524)
				(type default)
			)
			(layer "F.SilkS")
		)
		(fp_line
			(start 2.286 3.5179)
			(end 3.556 3.5179)
			(stroke
				(width 0.1524)
				(type default)
			)
			(layer "F.SilkS")
		)
		(fp_line
			(start -3.556 3.5179)
			(end -2.286 3.5179)
			(stroke
				(width 0.1524)
				(type default)
			)
			(layer "F.SilkS")
		)
		(fp_poly
			(pts
				(xy 3.556 -3.5179) (xy 2.5273 -3.5179) (xy 3.556 -2.4892)
			)
			(stroke
				(width 0)
				(type default)
			)
			(fill yes)
			(layer "F.SilkS")
		)
		(fp_rect
			(start -2.9972 2.5019)
			(end 2.9972 -2.5019)
			(stroke
				(width 0)
				(type default)
			)
			(fill no)
			(layer "F.CrtYd")
		)
		(fp_poly
			(pts
				(xy 3.556 -2.5019) (xy -2.9972 -2.5019) (xy -2.9972 2.5019) (xy 2.9972 2.5019) (xy 2.9972 -2.4892)
				(xy 3.556 -2.4892) (xy 3.556 3.5179) (xy -3.556 3.5179) (xy -3.556 -3.5179) (xy 3.556 -3.5179)
			)
			(stroke
				(width 0)
				(type default)
			)
			(fill no)
			(layer "F.CrtYd")
		)
		(fp_rect
			(start -3.556 3.5179)
			(end 3.556 -3.5179)
			(stroke
				(width 0)
				(type default)
			)
			(fill no)
			(layer "F.Fab")
		)
		(pad "1" smd rect
			(at 2.500122 -2.449322 90)
			(size 0.3048 1.1176)
			(layers "F.Cu" "F.Mask" "F.Paste")
			(net "P5VB_VFB")
		)
		(pad "2" smd rect
			(at 1.999996 -2.449322 90)
			(size 0.3048 1.1176)
			(layers "F.Cu" "F.Mask" "F.Paste")
			(net "P5VB_EN")
		)
		(pad "3" smd rect
			(at 1.500124 -2.449322 90)
			(size 0.3048 1.1176)
			(layers "F.Cu" "F.Mask" "F.Paste")
			(net "P5VB_PGD")
		)
		(pad "4" smd rect
			(at 0.999998 -2.449322 90)
			(size 0.3048 1.1176)
			(layers "F.Cu" "F.Mask" "F.Paste")
			(net "P5VB_VBST")
		)
		(pad "5" smd rect
			(at 0.500126 -2.449322 90)
			(size 0.3048 1.1176)
			(layers "F.Cu" "F.Mask" "F.Paste")
			(net "P5VB_ROVP")
		)
		(pad "6" smd rect
			(at 0 -2.449322 90)
			(size 0.3048 1.1176)
			(layers "F.Cu" "F.Mask" "F.Paste")
			(net "P5VB_LL")
		)
		(pad "7" smd rect
			(at -0.500126 -2.449322 90)
			(size 0.3048 1.1176)
			(layers "F.Cu" "F.Mask" "F.Paste")
			(net "P5VB_LL")
		)
		(pad "8" smd rect
			(at -0.999998 -2.449322 90)
			(size 0.3048 1.1176)
			(layers "F.Cu" "F.Mask" "F.Paste")
			(net "P5VB_LL")
		)
		(pad "9" smd rect
			(at -1.500124 -2.449322 90)
			(size 0.3048 1.1176)
			(layers "F.Cu" "F.Mask" "F.Paste")
			(net "P5VB_LL")
		)
		(pad "10" smd rect
			(at -1.999996 -2.449322 90)
			(size 0.3048 1.1176)
			(layers "F.Cu" "F.Mask" "F.Paste")
			(net "P5VB_LL")
		)
		(pad "11" smd rect
			(at -2.500122 -2.449322 90)
			(size 0.3048 1.1176)
			(layers "F.Cu" "F.Mask" "F.Paste")
			(net "P5VB_LL")
		)
		(pad "12" smd rect
			(at -2.500122 2.449322 90)
			(size 0.3048 1.1176)
			(layers "F.Cu" "F.Mask" "F.Paste")
			(net "P5VB_12VIN")
		)
		(pad "13" smd rect
			(at -1.999996 2.449322 90)
			(size 0.3048 1.1176)
			(layers "F.Cu" "F.Mask" "F.Paste")
			(net "P5VB_12VIN")
		)
		(pad "14" smd rect
			(at -1.500124 2.449322 90)
			(size 0.3048 1.1176)
			(layers "F.Cu" "F.Mask" "F.Paste")
			(net "P5VB_12VIN")
		)
		(pad "15" smd rect
			(at -0.999998 2.449322 90)
			(size 0.3048 1.1176)
			(layers "F.Cu" "F.Mask" "F.Paste")
			(net "P5VB_12VIN")
		)
		(pad "16" smd rect
			(at -0.500126 2.449322 90)
			(size 0.3048 1.1176)
			(layers "F.Cu" "F.Mask" "F.Paste")
			(net "P5VB_12VIN")
		)
		(pad "17" smd rect
			(at 0 2.449322 90)
			(size 0.3048 1.1176)
			(layers "F.Cu" "F.Mask" "F.Paste")
			(net "P5VB_12VIN")
		)
		(pad "18" smd rect
			(at 0.500126 2.449322 90)
			(size 0.3048 1.1176)
			(layers "F.Cu" "F.Mask" "F.Paste")
			(net "P5VB_VREG")
		)
		(pad "19" smd rect
			(at 0.999998 2.449322 90)
			(size 0.3048 1.1176)
			(layers "F.Cu" "F.Mask" "F.Paste")
			(net "P5VB_VDD")
		)
		(pad "20" smd rect
			(at 1.500124 2.449322 90)
			(size 0.3048 1.1176)
			(layers "F.Cu" "F.Mask" "F.Paste")
			(net "P5VB_MODE")
		)
		(pad "21" smd rect
			(at 1.999996 2.449322 90)
			(size 0.3048 1.1176)
			(layers "F.Cu" "F.Mask" "F.Paste")
			(net "P5VB_TRIP")
		)
		(pad "22" smd rect
			(at 2.500122 2.449322 90)
			(size 0.3048 1.1176)
			(layers "F.Cu" "F.Mask" "F.Paste")
			(net "P5VB_RF")
		)
		(pad "23" smd custom
			(at 0 0 90)
			(size 0.83185 0.83185)
			(layers "F.Cu" "F.Mask" "F.Paste")
			(net "GND")
			(options
				(clearance outline)
				(anchor circle)
			)
			(primitives
				(gr_poly
					(pts
						(xy -2.7813 1.6637) (xy -2.7813 1.2954) (xy -3.048 1.2954) (xy -3.048 0.9525) (xy -2.7813 0.9525)
						(xy -2.7813 -0.9525) (xy -3.048 -0.9525) (xy -3.048 -1.2954) (xy -2.7813 -1.2954) (xy -2.7813 -1.6637)
						(xy 2.7813 -1.6637) (xy 2.7813 -1.2954) (xy 3.048 -1.2954) (xy 3.048 -0.9525) (xy 2.7813 -0.9525)
						(xy 2.7813 0.9525) (xy 3.048 0.9525) (xy 3.048 1.2954) (xy 2.7813 1.2954) (xy 2.7813 1.6637)
					)
					(width 0)
					(fill yes)
				)
			)
		)
	)
)
